#ISCELL
  mstr_misc dns *
  *
#ISCELL
  mstr_symbols intel_corp_bpage *
  *
#ISCELL
  mstr_symbols pvddq_abc *
  page216_i1
#CELL
  mstr_discrete ir354xx *
  page216_i102
#CELL
  mstr_discrete ir354xx *
  page216_i103
#CELL
  mstr_discrete res *
  page216_i104
#ISCELL
  mstr_symbols gnd *
  page216_i105
#CELL
  mstr_discrete res *
  page216_i106
#ISCELL
  mstr_symbols gnd *
  page216_i107
#CELL
  dev_discrete cap_a *
  page216_i108
#ISCELL
  mstr_symbols gnd *
  page216_i109
#CELL
  dev_discrete cap_a *
  page216_i111
#ISCELL
  mstr_symbols gnd *
  page216_i112
#CELL
  w_hdl 3d01r5f-gp *
  page216_i114
#ISCELL
  mstr_symbols gnd *
  page216_i115
#ISCELL
  mstr_symbols gnd *
  page216_i117
#CELL
  mstr_discrete cap *
  page216_i118
#CELL
  w_hdl sc2k2p50v3kx-gp *
  page216_i119
#ISCELL
  mstr_symbols gnd *
  page216_i120
#CELL
  mstr_discrete cap *
  page216_i121
#ISCELL
  mstr_symbols gnd *
  page216_i122
#CELL
  w_hdl 3d01r5f-gp *
  page216_i123
#CELL
  w_hdl sc2k2p50v3kx-gp *
  page216_i124
#CELL
  mstr_discrete inductor *
  page216_i125
#CELL
  mstr_discrete res *
  page216_i126
#CELL
  mstr_discrete res *
  page216_i127
#CELL
  mstr_discrete cap *
  page216_i128
#ISCELL
  mstr_symbols gnd *
  page216_i19
#ISCELL
  mstr_standard offpage *
  page216_i3
#ISCELL
  mstr_standard offpage *
  page216_i33
#ISCELL
  mstr_symbols gnd *
  page216_i35
#ISCELL
  mstr_standard offpage *
  page216_i4
#CELL
  mstr_discrete cap *
  page216_i44
#CELL
  mstr_discrete cap *
  page216_i45
#CELL
  mstr_discrete cap *
  page216_i46
#CELL
  mstr_discrete cap *
  page216_i47
#CELL
  mstr_discrete cap *
  page216_i48
#CELL
  mstr_discrete cap *
  page216_i50
#CELL
  dev_discrete cap_a *
  page216_i51
#CELL
  mstr_discrete res *
  page216_i52
#CELL
  dev_discrete cap_a *
  page216_i53
#CELL
  mstr_discrete cap *
  page216_i54
#ISCELL
  mstr_standard offpage *
  page216_i58
#CELL
  mstr_discrete cap *
  page216_i6
#ISCELL
  mstr_standard offpage *
  page216_i61
#ISCELL
  mstr_standard offpage *
  page216_i62
#ISCELL
  mstr_standard offpage *
  page216_i63
#ISCELL
  mstr_symbols pvddq_abc *
  page216_i64
#CELL
  mstr_discrete inductor *
  page216_i65
#CELL
  mstr_discrete cap *
  page216_i68
#ISCELL
  mstr_symbols gnd *
  page216_i69
#ISCELL
  mstr_symbols gnd *
  page216_i7
#ISCELL
  mstr_symbols gnd *
  page216_i70
#CELL
  mstr_discrete cap *
  page216_i72
#CELL
  dev_discrete cap_a *
  page216_i73
#CELL
  mstr_discrete res *
  page216_i76
#CELL
  mstr_discrete cap *
  page216_i77
#CELL
  dev_discrete cap_a *
  page216_i78
#CELL
  mstr_discrete cap *
  page216_i79
#CELL
  mstr_discrete cap *
  page216_i80
#CELL
  mstr_discrete cap *
  page216_i81
#ISCELL
  mstr_standard offpage *
  page216_i82
#ISCELL
  mstr_symbols vcc_core *
  page216_i83
#CELL
  mstr_discrete cap *
  page216_i84
#ISCELL
  mstr_symbols gnd *
  page216_i85
#ISCELL
  mstr_symbols vcc_core *
  page216_i86
#ISCELL
  mstr_symbols p5v_stby *
  page216_i87
#ISCELL
  mstr_symbols p5v_stby *
  page216_i88
